# S9S_MB_2U (Grand Teton) — schematic netlist excerpt (pin names and nets, part order shuffled) for the footprints in the layout excerpt that follows; sources: Cadence DE-HDL packaged netlist, KiCad conversion of 03242023_DA0F0TMBIJ0_F0T_Motherboard_J_brd_V01_OCP.brd

R1355  Q_RES  100K 1% CHIP  pkg 0402LF  page 154 : A = RMII_BMC_OCP_TXD_1 ; B = GND
C1211  Q_CAP  100PF 50V 5% NPO  pkg 0402  page 220 : A = PWRGD_PCH_PWROK_R ; B = GND

(kicad_pcb
	(version 20260206)
	(generator "pcbnew")
	(generator_version "10.0")
	(general
		(thickness 1.6)
		(legacy_teardrops no)
	)
	(paper "A4")
	(title_block
		(title "03242023_DA0F0TMBIJ0_F0T_Motherboard_J_brd_V01_OCP.brd")
		(comment 1 "Grand Teton / footprints 2331-2332 of 6105")
	)
	(layers
		(0 "F.Cu" signal "TOP")
		(4 "In1.Cu" signal "GND")
		(6 "In2.Cu" signal "IN1")
		(8 "In3.Cu" signal "GND1")
		(10 "In4.Cu" signal "IN2")
		(12 "In5.Cu" signal "GND2")
		(14 "In6.Cu" signal "IN3")
		(16 "In7.Cu" signal "GND3")
		(18 "In8.Cu" signal "VCC")
		(20 "In9.Cu" signal "VCC1")
		(22 "In10.Cu" signal "GND4")
		(24 "In11.Cu" signal "IN4")
		(26 "In12.Cu" signal "GND5")
		(28 "In13.Cu" signal "IN5")
		(30 "In14.Cu" signal "GND6")
		(32 "In15.Cu" signal "IN6")
		(34 "In16.Cu" signal "GND7")
		(2 "B.Cu" signal "BOTTOM")
		(9 "F.Adhes" user "F.Adhesive")
		(11 "B.Adhes" user "B.Adhesive")
		(13 "F.Paste" user "Package Geometry/Pastemask Top")
		(15 "B.Paste" user "Package Geometry/Pastemask Bottom")
		(5 "F.SilkS" user "Ref Des/Silkscreen Top")
		(7 "B.SilkS" user "Ref Des/Silkscreen Bottom")
		(1 "F.Mask" user "Board Geometry/Soldermask Top")
		(3 "B.Mask" user "Board Geometry/Soldermask Bottom")
		(17 "Dwgs.User" user "User.Drawings")
		(19 "Cmts.User" user "User.Comments")
		(21 "Eco1.User" user "User.Eco1")
		(23 "Eco2.User" user "User.Eco2")
		(25 "Edge.Cuts" user "Board Geometry/Outline")
		(27 "Margin" user)
		(31 "F.CrtYd" user "Package Geometry/Place Bound Top")
		(29 "B.CrtYd" user "Package Geometry/Place Bound Bottom")
		(35 "F.Fab" user "Ref Des/Assembly Top")
		(33 "B.Fab" user "Ref Des/Assembly Bottom")
	)
	(footprint ""
		(layer "F.Cu")
		(at 211.99729 -69.86143)
		(property "Reference" "R1355"
			(at 0 0 0)
			(layer "F.SilkS")
			(hide yes)
			(effects
				(font
					(size 1.27 1.27)
				)
			)
		)
		(property "Value" ""
			(at 0 0 0)
			(layer "F.Fab")
			(effects
				(font
					(size 1.27 1.27)
				)
			)
		)
		(duplicate_pad_numbers_are_jumpers no)
		(fp_line
			(start -0.7874 -0.4064)
			(end 0.7874 -0.4064)
			(stroke
				(width 0.1524)
				(type default)
			)
			(layer "F.SilkS")
		)
		(fp_line
			(start -0.7874 0.4064)
			(end -0.7874 -0.4064)
			(stroke
				(width 0.1524)
				(type default)
			)
			(layer "F.SilkS")
		)
		(fp_line
			(start 0.7874 -0.4064)
			(end 0.7874 0.4064)
			(stroke
				(width 0.1524)
				(type default)
			)
			(layer "F.SilkS")
		)
		(fp_line
			(start 0.7874 0.4064)
			(end -0.7874 0.4064)
			(stroke
				(width 0.1524)
				(type default)
			)
			(layer "F.SilkS")
		)
		(fp_line
			(start -0.67945 -0.305054)
			(end -0.12065 -0.305054)
			(stroke
				(width 0.1)
				(type default)
			)
			(layer "F.Fab")
		)
		(fp_line
			(start -0.67945 0.3048)
			(end -0.67945 -0.305054)
			(stroke
				(width 0.1)
				(type default)
			)
			(layer "F.Fab")
		)
		(fp_line
			(start -0.12065 -0.305054)
			(end -0.12065 -0.2794)
			(stroke
				(width 0.1)
				(type default)
			)
			(layer "F.Fab")
		)
		(fp_line
			(start -0.12065 -0.2794)
			(end 0.12065 -0.2794)
			(stroke
				(width 0.1)
				(type default)
			)
			(layer "F.Fab")
		)
		(fp_line
			(start -0.12065 0.2794)
			(end -0.12065 0.3048)
			(stroke
				(width 0.1)
				(type default)
			)
			(layer "F.Fab")
		)
		(fp_line
			(start -0.12065 0.3048)
			(end -0.67945 0.3048)
			(stroke
				(width 0.1)
				(type default)
			)
			(layer "F.Fab")
		)
		(fp_line
			(start 0.120396 0.2794)
			(end -0.12065 0.2794)
			(stroke
				(width 0.1)
				(type default)
			)
			(layer "F.Fab")
		)
		(fp_line
			(start 0.120396 0.3048)
			(end 0.120396 0.2794)
			(stroke
				(width 0.1)
				(type default)
			)
			(layer "F.Fab")
		)
		(fp_line
			(start 0.12065 -0.3048)
			(end 0.67945 -0.3048)
			(stroke
				(width 0.1)
				(type default)
			)
			(layer "F.Fab")
		)
		(fp_line
			(start 0.12065 -0.2794)
			(end 0.12065 -0.3048)
			(stroke
				(width 0.1)
				(type default)
			)
			(layer "F.Fab")
		)
		(fp_line
			(start 0.67945 -0.3048)
			(end 0.67945 0.3048)
			(stroke
				(width 0.1)
				(type default)
			)
			(layer "F.Fab")
		)
		(fp_line
			(start 0.67945 0.3048)
			(end 0.120396 0.3048)
			(stroke
				(width 0.1)
				(type default)
			)
			(layer "F.Fab")
		)
		(pad "1" smd circle
			(at -0.40005 0)
			(size 0 0)
			(layers "F.Cu" "F.Mask" "F.Paste")
			(net "RMII_BMC_OCP_TXD_1")
		)
		(pad "2" smd circle
			(at 0.40005 0)
			(size 0 0)
			(layers "F.Cu" "F.Mask" "F.Paste")
			(net "GND")
		)
	)
	(footprint ""
		(layer "F.Cu")
		(at 175.31588 -130.266948 90)
		(property "Reference" "C1211"
			(at 0 0 90)
			(layer "F.SilkS")
			(hide yes)
			(effects
				(font
					(size 1.27 1.27)
				)
			)
		)
		(property "Value" ""
			(at 0 0 90)
			(layer "F.Fab")
			(effects
				(font
					(size 1.27 1.27)
				)
			)
		)
		(duplicate_pad_numbers_are_jumpers no)
		(fp_line
			(start 0.7874 -0.4064)
			(end 0.7874 0.4064)
			(stroke
				(width 0.1524)
				(type default)
			)
			(layer "F.SilkS")
		)
		(fp_line
			(start -0.7874 -0.4064)
			(end 0.7874 -0.4064)
			(stroke
				(width 0.1524)
				(type default)
			)
			(layer "F.SilkS")
		)
		(fp_line
			(start 0.7874 0.4064)
			(end -0.7874 0.4064)
			(stroke
				(width 0.1524)
				(type default)
			)
			(layer "F.SilkS")
		)
		(fp_line
			(start -0.7874 0.4064)
			(end -0.7874 -0.4064)
			(stroke
				(width 0.1524)
				(type default)
			)
			(layer "F.SilkS")
		)
		(fp_line
			(start -0.12065 -0.305054)
			(end -0.12065 -0.2794)
			(stroke
				(width 0.1)
				(type default)
			)
			(layer "F.Fab")
		)
		(fp_line
			(start -0.67945 -0.305054)
			(end -0.12065 -0.305054)
			(stroke
				(width 0.1)
				(type default)
			)
			(layer "F.Fab")
		)
		(fp_line
			(start 0.67945 -0.3048)
			(end 0.67945 0.3048)
			(stroke
				(width 0.1)
				(type default)
			)
			(layer "F.Fab")
		)
		(fp_line
			(start 0.12065 -0.3048)
			(end 0.67945 -0.3048)
			(stroke
				(width 0.1)
				(type default)
			)
			(layer "F.Fab")
		)
		(fp_line
			(start 0.12065 -0.2794)
			(end 0.12065 -0.3048)
			(stroke
				(width 0.1)
				(type default)
			)
			(layer "F.Fab")
		)
		(fp_line
			(start -0.12065 -0.2794)
			(end 0.12065 -0.2794)
			(stroke
				(width 0.1)
				(type default)
			)
			(layer "F.Fab")
		)
		(fp_line
			(start 0.120396 0.2794)
			(end -0.12065 0.2794)
			(stroke
				(width 0.1)
				(type default)
			)
			(layer "F.Fab")
		)
		(fp_line
			(start -0.12065 0.2794)
			(end -0.12065 0.3048)
			(stroke
				(width 0.1)
				(type default)
			)
			(layer "F.Fab")
		)
		(fp_line
			(start 0.67945 0.3048)
			(end 0.120396 0.3048)
			(stroke
				(width 0.1)
				(type default)
			)
			(layer "F.Fab")
		)
		(fp_line
			(start 0.120396 0.3048)
			(end 0.120396 0.2794)
			(stroke
				(width 0.1)
				(type default)
			)
			(layer "F.Fab")
		)
		(fp_line
			(start -0.12065 0.3048)
			(end -0.67945 0.3048)
			(stroke
				(width 0.1)
				(type default)
			)
			(layer "F.Fab")
		)
		(fp_line
			(start -0.67945 0.3048)
			(end -0.67945 -0.305054)
			(stroke
				(width 0.1)
				(type default)
			)
			(layer "F.Fab")
		)
		(pad "1" smd circle
			(at -0.40005 0 90)
			(size 0 0)
			(layers "F.Cu" "F.Mask" "F.Paste")
			(net "PWRGD_PCH_PWROK_R")
		)
		(pad "2" smd circle
			(at 0.40005 0 90)
			(size 0 0)
			(layers "F.Cu" "F.Mask" "F.Paste")
			(net "GND")
		)
	)
)
